(kicad_pcb
	(version 20260206)
	(generator "pcbnew")
	(generator_version "10.0")
	(general
		(thickness 1.21888)
		(legacy_teardrops no)
	)
	(paper "A4")
	(title_block
		(title "timecard-v9 — TimeCard-DC-V9_EXP.PcbDoc")
		(comment 1 "Time Appliance Project (Time Card) / footprints 70-73 of 402")
	)
	(layers
		(0 "F.Cu" signal "TOP")
		(4 "In1.Cu" signal "SGND")
		(6 "In2.Cu" signal "IN1")
		(8 "In3.Cu" signal "IN2")
		(10 "In4.Cu" signal "SGND1")
		(2 "B.Cu" signal "BOTTOM")
		(9 "F.Adhes" user "F.Adhesive")
		(11 "B.Adhes" user "B.Adhesive")
		(13 "F.Paste" user "Top Paste")
		(15 "B.Paste" user "Bottom Paste")
		(5 "F.SilkS" user "Top Overlay")
		(7 "B.SilkS" user "Bottom Overlay")
		(1 "F.Mask" user "Top Solder")
		(3 "B.Mask" user "Bottom Solder")
		(17 "Dwgs.User" user "User.Drawings")
		(19 "Cmts.User" user "User.Comments")
		(21 "Eco1.User" user "User.Eco1")
		(23 "Eco2.User" user "User.Eco2")
		(25 "Edge.Cuts" user)
		(27 "Margin" user)
		(31 "F.CrtYd" user "Top Courtyard")
		(29 "B.CrtYd" user "Bottom Courtyard")
		(35 "F.Fab" user "Top Component Center")
		(33 "B.Fab" user "Bottom Component Center")
	)
	(footprint "Vault:FP-2199119-3-MFG"
		(locked yes)
		(layer "F.Cu")
		(at 120.2466 65.0162 90)
		(property "Reference" "J44"
			(at -7.0032 6.448069 270)
			(unlocked yes)
			(layer "F.SilkS")
			(effects
				(font
					(size 0.762 0.762)
					(thickness 0.2032)
				)
			)
		)
		(property "Value" "2199119-3"
			(at -12.739871 1.153685 0)
			(unlocked yes)
			(layer "F.SilkS")
			(hide yes)
			(effects
				(font
					(size 0.762 0.762)
					(thickness 0.2032)
				)
			)
		)
		(sheetname "10-M2_GPS")
		(sheetfile "10-M2_GPS.kicad_sch")
		(duplicate_pad_numbers_are_jumpers no)
		(fp_line
			(start -6.225 -3.975)
			(end -4.775 -3.975)
			(stroke
				(width 0.2)
				(type solid)
			)
			(layer "F.SilkS")
		)
		(fp_line
			(start 11 -1.375)
			(end 11 0.2)
			(stroke
				(width 0.2)
				(type solid)
			)
			(layer "F.SilkS")
		)
		(fp_line
			(start -11 -1.375)
			(end -11 3.975)
			(stroke
				(width 0.2)
				(type solid)
			)
			(layer "F.SilkS")
		)
		(fp_line
			(start 11 2.55)
			(end 11 3.975)
			(stroke
				(width 0.2)
				(type solid)
			)
			(layer "F.SilkS")
		)
		(fp_line
			(start 9.525 3.975)
			(end 11 3.975)
			(stroke
				(width 0.2)
				(type solid)
			)
			(layer "F.SilkS")
		)
		(fp_line
			(start -6.475 3.975)
			(end -5.025 3.975)
			(stroke
				(width 0.2)
				(type solid)
			)
			(layer "F.SilkS")
		)
		(fp_line
			(start -11 3.975)
			(end -9.525 3.975)
			(stroke
				(width 0.2)
				(type solid)
			)
			(layer "F.SilkS")
		)
		(fp_circle
			(center -9.275 -5.275)
			(end -9.15 -5.275)
			(stroke
				(width 0.25)
				(type solid)
			)
			(fill no)
			(layer "F.SilkS")
		)
		(fp_line
			(start 11.1 -4.775)
			(end 11.1 4.525)
			(stroke
				(width 0.2)
				(type solid)
			)
			(layer "F.CrtYd")
		)
		(fp_line
			(start -11.1 -4.775)
			(end 11.1 -4.775)
			(stroke
				(width 0.2)
				(type solid)
			)
			(layer "F.CrtYd")
		)
		(fp_line
			(start -11.1 -4.775)
			(end -11.1 4.525)
			(stroke
				(width 0.2)
				(type solid)
			)
			(layer "F.CrtYd")
		)
		(fp_line
			(start -11.1 4.525)
			(end 11.1 4.525)
			(stroke
				(width 0.2)
				(type solid)
			)
			(layer "F.CrtYd")
		)
		(fp_line
			(start 11.1 -4.775)
			(end 11.1 4.525)
			(stroke
				(width 0.2)
				(type solid)
			)
			(layer "F.Fab")
		)
		(fp_line
			(start -11.1 -4.775)
			(end 11.1 -4.775)
			(stroke
				(width 0.2)
				(type solid)
			)
			(layer "F.Fab")
		)
		(fp_line
			(start -11.1 -4.775)
			(end -11.1 4.525)
			(stroke
				(width 0.2)
				(type solid)
			)
			(layer "F.Fab")
		)
		(fp_line
			(start 0 -0.5)
			(end 0 0.5)
			(stroke
				(width 0.1)
				(type solid)
			)
			(layer "F.Fab")
		)
		(fp_line
			(start -0.5 0)
			(end 0.5 0)
			(stroke
				(width 0.1)
				(type solid)
			)
			(layer "F.Fab")
		)
		(fp_line
			(start -11.1 4.525)
			(end 11.1 4.525)
			(stroke
				(width 0.2)
				(type solid)
			)
			(layer "F.Fab")
		)
		(fp_text user "${REFERENCE}"
			(at -0.00185 0.15925 90)
			(unlocked yes)
			(layer "F.Fab")
			(effects
				(font
					(face "Arial")
					(size 0.63 0.63)
					(thickness 0.1)
				)
				(justify left bottom)
			)
		)
		(pad "" np_thru_hole circle
			(at -10 1.375 90)
			(size 1.1 1.1)
			(drill 1.1)
			(layers "*.Cu" "*.Mask")
			(solder_mask_margin 0)
			(solder_paste_margin -1000)
			(thermal_bridge_angle 90)
		)
		(pad "" np_thru_hole circle
			(at 10 1.375 90)
			(size 1.6 1.6)
			(drill 1.6)
			(layers "*.Cu" "*.Mask")
			(solder_mask_margin 0)
			(solder_paste_margin -1000)
			(thermal_bridge_angle 90)
		)
		(pad "1" smd rect
			(at -9.25 -3.9 90)
			(size 0.3 1.55)
			(layers "F.Cu" "F.Mask" "F.Paste")
			(solder_mask_margin 0)
			(solder_paste_margin 0)
		)
		(pad "2" smd rect
			(at -9 3.65 90)
			(size 0.3 1.55)
			(layers "F.Cu" "F.Mask" "F.Paste")
			(net "+3.3V")
			(solder_mask_margin 0)
			(solder_paste_margin 0)
		)
		(pad "3" smd rect
			(at -8.75 -3.9 90)
			(size 0.3 1.55)
			(layers "F.Cu" "F.Mask" "F.Paste")
			(net "GND")
			(solder_mask_margin 0)
			(solder_paste_margin 0)
		)
		(pad "4" smd rect
			(at -8.5 3.65 90)
			(size 0.3 1.55)
			(layers "F.Cu" "F.Mask" "F.Paste")
			(net "+3.3V")
			(solder_mask_margin 0)
			(solder_paste_margin 0)
		)
		(pad "5" smd rect
			(at -8.25 -3.9 90)
			(size 0.3 1.55)
			(layers "F.Cu" "F.Mask" "F.Paste")
			(net "GND")
			(solder_mask_margin 0)
			(solder_paste_margin 0)
		)
		(pad "6" smd rect
			(at -8 3.65 90)
			(size 0.3 1.55)
			(layers "F.Cu" "F.Mask" "F.Paste")
			(solder_mask_margin 0)
			(solder_paste_margin 0)
		)
		(pad "7" smd rect
			(at -7.75 -3.9 90)
			(size 0.3 1.55)
			(layers "F.Cu" "F.Mask" "F.Paste")
			(solder_mask_margin 0)
			(solder_paste_margin 0)
		)
		(pad "8" smd rect
			(at -7.5 3.65 90)
			(size 0.3 1.55)
			(layers "F.Cu" "F.Mask" "F.Paste")
			(solder_mask_margin 0)
			(solder_paste_margin 0)
		)
		(pad "9" smd rect
			(at -7.25 -3.9 90)
			(size 0.3 1.55)
			(layers "F.Cu" "F.Mask" "F.Paste")
			(solder_mask_margin 0)
			(solder_paste_margin 0)
		)
		(pad "10" smd rect
			(at -7 3.65 90)
			(size 0.3 1.55)
			(layers "F.Cu" "F.Mask" "F.Paste")
			(solder_mask_margin 0)
			(solder_paste_margin 0)
		)
		(pad "11" smd rect
			(at -6.75 -3.9 90)
			(size 0.3 1.55)
			(layers "F.Cu" "F.Mask" "F.Paste")
			(net "GND")
			(solder_mask_margin 0)
			(solder_paste_margin 0)
		)
		(pad "20" smd rect
			(at -4.5 3.65 90)
			(size 0.3 1.55)
			(layers "F.Cu" "F.Mask" "F.Paste")
			(net "M2_GPS1_PIN11")
			(solder_mask_margin 0)
			(solder_paste_margin 0)
		)
		(pad "21" smd rect
			(at -4.25 -3.9 90)
			(size 0.3 1.55)
			(layers "F.Cu" "F.Mask" "F.Paste")
			(solder_mask_margin 0)
			(solder_paste_margin 0)
		)
		(pad "22" smd rect
			(at -4 3.65 90)
			(size 0.3 1.55)
			(layers "F.Cu" "F.Mask" "F.Paste")
			(net "M2_GPS1_PIN12")
			(solder_mask_margin 0)
			(solder_paste_margin 0)
		)
		(pad "23" smd rect
			(at -3.75 -3.9 90)
			(size 0.3 1.55)
			(layers "F.Cu" "F.Mask" "F.Paste")
			(solder_mask_margin 0)
			(solder_paste_margin 0)
		)
		(pad "24" smd rect
			(at -3.5 3.65 90)
			(size 0.3 1.55)
			(layers "F.Cu" "F.Mask" "F.Paste")
			(solder_mask_margin 0)
			(solder_paste_margin 0)
		)
		(pad "25" smd rect
			(at -3.25 -3.9 90)
			(size 0.3 1.55)
			(layers "F.Cu" "F.Mask" "F.Paste")
			(solder_mask_margin 0)
			(solder_paste_margin 0)
		)
		(pad "26" smd rect
			(at -3 3.65 90)
			(size 0.3 1.55)
			(layers "F.Cu" "F.Mask" "F.Paste")
			(solder_mask_margin 0)
			(solder_paste_margin 0)
		)
		(pad "27" smd rect
			(at -2.75 -3.9 90)
			(size 0.3 1.55)
			(layers "F.Cu" "F.Mask" "F.Paste")
			(net "GND")
			(solder_mask_margin 0)
			(solder_paste_margin 0)
		)
		(pad "28" smd rect
			(at -2.5 3.65 90)
			(size 0.3 1.55)
			(layers "F.Cu" "F.Mask" "F.Paste")
			(solder_mask_margin 0)
			(solder_paste_margin 0)
		)
		(pad "29" smd rect
			(at -2.25 -3.9 90)
			(size 0.3 1.55)
			(layers "F.Cu" "F.Mask" "F.Paste")
			(solder_mask_margin 0)
			(solder_paste_margin 0)
		)
		(pad "30" smd rect
			(at -2 3.65 90)
			(size 0.3 1.55)
			(layers "F.Cu" "F.Mask" "F.Paste")
			(solder_mask_margin 0)
			(solder_paste_margin 0)
		)
		(pad "31" smd rect
			(at -1.75 -3.9 90)
			(size 0.3 1.55)
			(layers "F.Cu" "F.Mask" "F.Paste")
			(solder_mask_margin 0)
			(solder_paste_margin 0)
		)
		(pad "32" smd rect
			(at -1.5 3.65 90)
			(size 0.3 1.55)
			(layers "F.Cu" "F.Mask" "F.Paste")
			(solder_mask_margin 0)
			(solder_paste_margin 0)
		)
		(pad "33" smd rect
			(at -1.25 -3.9 90)
			(size 0.3 1.55)
			(layers "F.Cu" "F.Mask" "F.Paste")
			(net "GND")
			(solder_mask_margin 0)
			(solder_paste_margin 0)
		)
		(pad "34" smd rect
			(at -1 3.65 90)
			(size 0.3 1.55)
			(layers "F.Cu" "F.Mask" "F.Paste")
			(solder_mask_margin 0)
			(solder_paste_margin 0)
		)
		(pad "35" smd rect
			(at -0.75 -3.9 90)
			(size 0.3 1.55)
			(layers "F.Cu" "F.Mask" "F.Paste")
			(net "NetJ44_35")
			(solder_mask_margin 0)
			(solder_paste_margin 0)
		)
		(pad "36" smd rect
			(at -0.5 3.65 90)
			(size 0.3 1.55)
			(layers "F.Cu" "F.Mask" "F.Paste")
			(solder_mask_margin 0)
			(solder_paste_margin 0)
		)
		(pad "37" smd rect
			(at -0.25 -3.9 90)
			(size 0.3 1.55)
			(layers "F.Cu" "F.Mask" "F.Paste")
			(solder_mask_margin 0)
			(solder_paste_margin 0)
		)
		(pad "38" smd rect
			(at 0 3.65 90)
			(size 0.3 1.55)
			(layers "F.Cu" "F.Mask" "F.Paste")
			(solder_mask_margin 0)
			(solder_paste_margin 0)
		)
		(pad "39" smd rect
			(at 0.25 -3.9 90)
			(size 0.3 1.55)
			(layers "F.Cu" "F.Mask" "F.Paste")
			(net "GND")
			(solder_mask_margin 0)
			(solder_paste_margin 0)
		)
		(pad "40" smd rect
			(at 0.5 3.65 90)
			(size 0.3 1.55)
			(layers "F.Cu" "F.Mask" "F.Paste")
			(net "GPS1_PIN13")
			(solder_mask_margin 0)
			(solder_paste_margin 0)
		)
		(pad "41" smd rect
			(at 0.75 -3.9 90)
			(size 0.3 1.55)
			(layers "F.Cu" "F.Mask" "F.Paste")
			(solder_mask_margin 0)
			(solder_paste_margin 0)
		)
		(pad "42" smd rect
			(at 1 3.65 90)
			(size 0.3 1.55)
			(layers "F.Cu" "F.Mask" "F.Paste")
			(net "GPS1_PIN14")
			(solder_mask_margin 0)
			(solder_paste_margin 0)
		)
		(pad "43" smd rect
			(at 1.25 -3.9 90)
			(size 0.3 1.55)
			(layers "F.Cu" "F.Mask" "F.Paste")
			(solder_mask_margin 0)
			(solder_paste_margin 0)
		)
		(pad "44" smd rect
			(at 1.5 3.65 90)
			(size 0.3 1.55)
			(layers "F.Cu" "F.Mask" "F.Paste")
			(net "GPS1_PIN15")
			(solder_mask_margin 0)
			(solder_paste_margin 0)
		)
		(pad "45" smd rect
			(at 1.75 -3.9 90)
			(size 0.3 1.55)
			(layers "F.Cu" "F.Mask" "F.Paste")
			(net "GND")
			(solder_mask_margin 0)
			(solder_paste_margin 0)
		)
		(pad "46" smd rect
			(at 2 3.65 90)
			(size 0.3 1.55)
			(layers "F.Cu" "F.Mask" "F.Paste")
			(net "NetJ44_46")
			(solder_mask_margin 0)
			(solder_paste_margin 0)
		)
		(pad "47" smd rect
			(at 2.25 -3.9 90)
			(size 0.3 1.55)
			(layers "F.Cu" "F.Mask" "F.Paste")
			(solder_mask_margin 0)
			(solder_paste_margin 0)
		)
		(pad "48" smd rect
			(at 2.5 3.65 90)
			(size 0.3 1.55)
			(layers "F.Cu" "F.Mask" "F.Paste")
			(net "M2_GPS1_TP2")
			(solder_mask_margin 0)
			(solder_paste_margin 0)
		)
		(pad "49" smd rect
			(at 2.75 -3.9 90)
			(size 0.3 1.55)
			(layers "F.Cu" "F.Mask" "F.Paste")
			(solder_mask_margin 0)
			(solder_paste_margin 0)
		)
		(pad "50" smd rect
			(at 3 3.65 90)
			(size 0.3 1.55)
			(layers "F.Cu" "F.Mask" "F.Paste")
			(net "GPS1_RST")
			(solder_mask_margin 0)
			(solder_paste_margin 0)
		)
		(pad "51" smd rect
			(at 3.25 -3.9 90)
			(size 0.3 1.55)
			(layers "F.Cu" "F.Mask" "F.Paste")
			(net "GND")
			(solder_mask_margin 0)
			(solder_paste_margin 0)
		)
		(pad "52" smd rect
			(at 3.5 3.65 90)
			(size 0.3 1.55)
			(layers "F.Cu" "F.Mask" "F.Paste")
			(solder_mask_margin 0)
			(solder_paste_margin 0)
		)
		(pad "53" smd rect
			(at 3.75 -3.9 90)
			(size 0.3 1.55)
			(layers "F.Cu" "F.Mask" "F.Paste")
			(solder_mask_margin 0)
			(solder_paste_margin 0)
		)
		(pad "54" smd rect
			(at 4 3.65 90)
			(size 0.3 1.55)
			(layers "F.Cu" "F.Mask" "F.Paste")
			(solder_mask_margin 0)
			(solder_paste_margin 0)
		)
		(pad "55" smd rect
			(at 4.25 -3.9 90)
			(size 0.3 1.55)
			(layers "F.Cu" "F.Mask" "F.Paste")
			(solder_mask_margin 0)
			(solder_paste_margin 0)
		)
		(pad "56" smd rect
			(at 4.5 3.65 90)
			(size 0.3 1.55)
			(layers "F.Cu" "F.Mask" "F.Paste")
			(solder_mask_margin 0)
			(solder_paste_margin 0)
		)
		(pad "57" smd rect
			(at 4.75 -3.9 90)
			(size 0.3 1.55)
			(layers "F.Cu" "F.Mask" "F.Paste")
			(net "GND")
			(solder_mask_margin 0)
			(solder_paste_margin 0)
		)
		(pad "58" smd rect
			(at 5 3.65 90)
			(size 0.3 1.55)
			(layers "F.Cu" "F.Mask" "F.Paste")
			(solder_mask_margin 0)
			(solder_paste_margin 0)
		)
		(pad "59" smd rect
			(at 5.25 -3.9 90)
			(size 0.3 1.55)
			(layers "F.Cu" "F.Mask" "F.Paste")
			(solder_mask_margin 0)
			(solder_paste_margin 0)
		)
		(pad "60" smd rect
			(at 5.5 3.65 90)
			(size 0.3 1.55)
			(layers "F.Cu" "F.Mask" "F.Paste")
			(solder_mask_margin 0)
			(solder_paste_margin 0)
		)
		(pad "61" smd rect
			(at 5.75 -3.9 90)
			(size 0.3 1.55)
			(layers "F.Cu" "F.Mask" "F.Paste")
			(solder_mask_margin 0)
			(solder_paste_margin 0)
		)
		(pad "62" smd rect
			(at 6 3.65 90)
			(size 0.3 1.55)
			(layers "F.Cu" "F.Mask" "F.Paste")
			(net "M2_GPS1_RX")
			(solder_mask_margin 0)
			(solder_paste_margin 0)
		)
		(pad "63" smd rect
			(at 6.25 -3.9 90)
			(size 0.3 1.55)
			(layers "F.Cu" "F.Mask" "F.Paste")
			(solder_mask_margin 0)
			(solder_paste_margin 0)
		)
		(pad "64" smd rect
			(at 6.5 3.65 90)
			(size 0.3 1.55)
			(layers "F.Cu" "F.Mask" "F.Paste")
			(net "M2_GPS1_TX")
			(solder_mask_margin 0)
			(solder_paste_margin 0)
		)
		(pad "65" smd rect
			(at 6.75 -3.9 90)
			(size 0.3 1.55)
			(layers "F.Cu" "F.Mask" "F.Paste")
			(solder_mask_margin 0)
			(solder_paste_margin 0)
		)
		(pad "66" smd rect
			(at 7 3.65 90)
			(size 0.3 1.55)
			(layers "F.Cu" "F.Mask" "F.Paste")
			(solder_mask_margin 0)
			(solder_paste_margin 0)
		)
		(pad "67" smd rect
			(at 7.25 -3.9 90)
			(size 0.3 1.55)
			(layers "F.Cu" "F.Mask" "F.Paste")
			(net "GPS1_RST")
			(solder_mask_margin 0)
			(solder_paste_margin 0)
		)
		(pad "68" smd rect
			(at 7.5 3.65 90)
			(size 0.3 1.55)
			(layers "F.Cu" "F.Mask" "F.Paste")
			(solder_mask_margin 0)
			(solder_paste_margin 0)
		)
		(pad "69" smd rect
			(at 7.75 -3.9 90)
			(size 0.3 1.55)
			(layers "F.Cu" "F.Mask" "F.Paste")
			(solder_mask_margin 0)
			(solder_paste_margin 0)
		)
		(pad "70" smd rect
			(at 8 3.65 90)
			(size 0.3 1.55)
			(layers "F.Cu" "F.Mask" "F.Paste")
			(net "+3.3V")
			(solder_mask_margin 0)
			(solder_paste_margin 0)
		)
		(pad "71" smd rect
			(at 8.25 -3.9 90)
			(size 0.3 1.55)
			(layers "F.Cu" "F.Mask" "F.Paste")
			(net "GND")
			(solder_mask_margin 0)
			(solder_paste_margin 0)
		)
		(pad "72" smd rect
			(at 8.5 3.65 90)
			(size 0.3 1.55)
			(layers "F.Cu" "F.Mask" "F.Paste")
			(net "+3.3V")
			(solder_mask_margin 0)
			(solder_paste_margin 0)
		)
		(pad "73" smd rect
			(at 8.75 -3.9 90)
			(size 0.3 1.55)
			(layers "F.Cu" "F.Mask" "F.Paste")
			(net "GND")
			(solder_mask_margin 0)
			(solder_paste_margin 0)
		)
		(pad "74" smd rect
			(at 9 3.65 90)
			(size 0.3 1.55)
			(layers "F.Cu" "F.Mask" "F.Paste")
			(net "+3.3V")
			(solder_mask_margin 0)
			(solder_paste_margin 0)
		)
		(pad "75" smd rect
			(at 9.25 -3.9 90)
			(size 0.3 1.55)
			(layers "F.Cu" "F.Mask" "F.Paste")
			(solder_mask_margin 0)
			(solder_paste_margin 0)
		)
		(pad "76" smd rect
			(at -10.35 -3.125 90)
			(size 1.2 2.75)
			(layers "F.Cu" "F.Mask" "F.Paste")
			(net "GND")
			(solder_mask_margin 0)
			(solder_paste_margin 0)
		)
		(pad "77" smd rect
			(at 10.35 -3.125 90)
			(size 1.2 2.75)
			(layers "F.Cu" "F.Mask" "F.Paste")
			(net "GND")
			(solder_mask_margin 0)
			(solder_paste_margin 0)
		)
	)
	(footprint "Vault:RESC1005X40X25LL05T10"
		(layer "F.Cu")
		(at 194.0216 125.7162 90)
		(property "Reference" "R169"
			(at -0.2968 -2.373079 90)
			(unlocked yes)
			(layer "F.SilkS")
			(effects
				(font
					(size 0.762 0.762)
					(thickness 0.2032)
				)
			)
		)
		(property "Value" "DNI_49.9_1%_0402"
			(at -2.579871 11.71832 0)
			(unlocked yes)
			(layer "F.SilkS")
			(hide yes)
			(effects
				(font
					(size 0.762 0.762)
					(thickness 0.2032)
				)
			)
		)
		(sheetname "11-M2_RCB_MUX")
		(sheetfile "11-M2_RCB_MUX.kicad_sch")
		(duplicate_pad_numbers_are_jumpers no)
		(pad "1" smd rect
			(at -0.375 0 180)
			(size 0.45 0.5)
			(layers "F.Cu" "F.Mask" "F.Paste")
			(net "GPS2_PIN12")
		)
		(pad "2" smd rect
			(at 0.375 0 180)
			(size 0.45 0.5)
			(layers "F.Cu" "F.Mask" "F.Paste")
			(net "M2_GPS2_PIN12")
		)
	)
	(footprint "Vault:TECO-1909763-1_V"
		(layer "F.Cu")
		(at 77.19563 121.8662 -90)
		(property "Reference" "J3"
			(at -3.123079 0.245425 0)
			(unlocked yes)
			(layer "F.SilkS")
			(effects
				(font
					(size 0.762 0.762)
					(thickness 0.2286)
				)
			)
		)
		(property "Value" "1909763-1"
			(at 4.582685 3.722871 270)
			(unlocked yes)
			(layer "F.SilkS")
			(hide yes)
			(effects
				(font
					(size 0.762 0.762)
					(thickness 0.2286)
				)
			)
		)
		(sheetname "01-USER_IO")
		(sheetfile "01-USER_IO.kicad_sch")
		(duplicate_pad_numbers_are_jumpers no)
		(fp_line
			(start 0.55 -1.3)
			(end -0.55 -1.3)
			(stroke
				(width 0.2)
				(type solid)
			)
			(layer "F.SilkS")
		)
		(fp_circle
			(center -1.778 1.65)
			(end -1.903 1.65)
			(stroke
				(width 0.25)
				(type solid)
			)
			(fill no)
			(layer "F.SilkS")
		)
		(pad "1" smd rect
			(at -1.475 0 270)
			(size 1.05 2.2)
			(layers "F.Cu" "F.Mask" "F.Paste")
			(net "GND")
		)
		(pad "2" smd rect
			(at 0 1.525 270)
			(size 1 1.05)
			(layers "F.Cu" "F.Mask" "F.Paste")
			(net "NetAN3_1")
		)
		(pad "3" smd rect
			(at 1.475 0 270)
			(size 1.05 2.2)
			(layers "F.Cu" "F.Mask" "F.Paste")
			(net "GND")
		)
	)
	(footprint "Vault:RESC1005X40X25LL05T10"
		(layer "F.Cu")
		(at 122.6216 81.2162 180)
		(property "Reference" "R174"
			(at -2.85558 0.075489 0)
			(unlocked yes)
			(layer "F.SilkS")
			(effects
				(font
					(size 0.762 0.762)
					(thickness 0.2032)
				)
			)
		)
		(property "Value" "DNI_49.9_1%_0402"
			(at -2.579871 11.71832 90)
			(unlocked yes)
			(layer "F.SilkS")
			(hide yes)
			(effects
				(font
					(size 0.762 0.762)
					(thickness 0.2032)
				)
			)
		)
		(sheetname "11-M2_RCB_MUX")
		(sheetfile "11-M2_RCB_MUX.kicad_sch")
		(duplicate_pad_numbers_are_jumpers no)
		(pad "1" smd rect
			(at -0.375 0 270)
			(size 0.45 0.5)
			(layers "F.Cu" "F.Mask" "F.Paste")
			(net "GPS1_PIN12")
		)
		(pad "2" smd rect
			(at 0.375 0 270)
			(size 0.45 0.5)
			(layers "F.Cu" "F.Mask" "F.Paste")
			(net "M2_GPS1_PIN12")
		)
	)
)
